(kicad_pcb
	(version 20260206)
	(generator "pcbnew")
	(generator_version "10.0")
	(general
		(thickness 1.6)
		(legacy_teardrops no)
	)
	(paper "A4")
	(title_block
		(title "01162023_DA0F0TEBIF0_F0T_Expander_BD_F_brd_V02_OCP.brd")
		(comment 1 "Grand Teton / footprints 6110-6116 of 9728")
	)
	(layers
		(0 "F.Cu" signal "TOP")
		(4 "In1.Cu" signal "GND")
		(6 "In2.Cu" signal "VCC")
		(8 "In3.Cu" signal "VCC1")
		(10 "In4.Cu" signal "GND1")
		(12 "In5.Cu" signal "IN1")
		(14 "In6.Cu" signal "GND2")
		(16 "In7.Cu" signal "IN2")
		(18 "In8.Cu" signal "GND3")
		(20 "In9.Cu" signal "IN3")
		(22 "In10.Cu" signal "GND4")
		(24 "In11.Cu" signal "IN4")
		(26 "In12.Cu" signal "GND5")
		(28 "In13.Cu" signal "IN5")
		(30 "In14.Cu" signal "GND6")
		(32 "In15.Cu" signal "IN6")
		(34 "In16.Cu" signal "GND7")
		(2 "B.Cu" signal "BOTTOM")
		(9 "F.Adhes" user "F.Adhesive")
		(11 "B.Adhes" user "B.Adhesive")
		(13 "F.Paste" user "Package Geometry/Pastemask Top")
		(15 "B.Paste" user "Package Geometry/Pastemask Bottom")
		(5 "F.SilkS" user "Ref Des/Silkscreen Top")
		(7 "B.SilkS" user "Ref Des/Silkscreen Bottom")
		(1 "F.Mask" user "Board Geometry/Soldermask Top")
		(3 "B.Mask" user "Board Geometry/Soldermask Bottom")
		(17 "Dwgs.User" user "User.Drawings")
		(19 "Cmts.User" user "User.Comments")
		(21 "Eco1.User" user "User.Eco1")
		(23 "Eco2.User" user "User.Eco2")
		(25 "Edge.Cuts" user "Board Geometry/Outline")
		(27 "Margin" user)
		(31 "F.CrtYd" user "Package Geometry/Place Bound Top")
		(29 "B.CrtYd" user "Package Geometry/Place Bound Bottom")
		(35 "F.Fab" user "Ref Des/Assembly Top")
		(33 "B.Fab" user "Ref Des/Assembly Bottom")
	)
	(footprint ""
		(layer "F.Cu")
		(at 258.891278 -346.703142 -90)
		(property "Reference" "R6649"
			(at 0 0 270)
			(layer "F.SilkS")
			(hide yes)
			(effects
				(font
					(size 1.27 1.27)
				)
			)
		)
		(property "Value" ""
			(at 0 0 270)
			(layer "F.Fab")
			(effects
				(font
					(size 1.27 1.27)
				)
			)
		)
		(duplicate_pad_numbers_are_jumpers no)
		(fp_line
			(start -0.7874 0.4064)
			(end -0.7874 -0.4064)
			(stroke
				(width 0.1524)
				(type default)
			)
			(layer "F.SilkS")
		)
		(fp_line
			(start 0.7874 0.4064)
			(end -0.7874 0.4064)
			(stroke
				(width 0.1524)
				(type default)
			)
			(layer "F.SilkS")
		)
		(fp_line
			(start -0.7874 -0.4064)
			(end 0.7874 -0.4064)
			(stroke
				(width 0.1524)
				(type default)
			)
			(layer "F.SilkS")
		)
		(fp_line
			(start 0.7874 -0.4064)
			(end 0.7874 0.4064)
			(stroke
				(width 0.1524)
				(type default)
			)
			(layer "F.SilkS")
		)
		(fp_line
			(start -0.67945 0.3048)
			(end -0.67945 -0.305054)
			(stroke
				(width 0.1)
				(type default)
			)
			(layer "F.Fab")
		)
		(fp_line
			(start -0.12065 0.3048)
			(end -0.67945 0.3048)
			(stroke
				(width 0.1)
				(type default)
			)
			(layer "F.Fab")
		)
		(fp_line
			(start 0.120396 0.3048)
			(end 0.120396 0.2794)
			(stroke
				(width 0.1)
				(type default)
			)
			(layer "F.Fab")
		)
		(fp_line
			(start 0.67945 0.3048)
			(end 0.120396 0.3048)
			(stroke
				(width 0.1)
				(type default)
			)
			(layer "F.Fab")
		)
		(fp_line
			(start -0.12065 0.2794)
			(end -0.12065 0.3048)
			(stroke
				(width 0.1)
				(type default)
			)
			(layer "F.Fab")
		)
		(fp_line
			(start 0.120396 0.2794)
			(end -0.12065 0.2794)
			(stroke
				(width 0.1)
				(type default)
			)
			(layer "F.Fab")
		)
		(fp_line
			(start -0.12065 -0.2794)
			(end 0.12065 -0.2794)
			(stroke
				(width 0.1)
				(type default)
			)
			(layer "F.Fab")
		)
		(fp_line
			(start 0.12065 -0.2794)
			(end 0.12065 -0.3048)
			(stroke
				(width 0.1)
				(type default)
			)
			(layer "F.Fab")
		)
		(fp_line
			(start 0.12065 -0.3048)
			(end 0.67945 -0.3048)
			(stroke
				(width 0.1)
				(type default)
			)
			(layer "F.Fab")
		)
		(fp_line
			(start 0.67945 -0.3048)
			(end 0.67945 0.3048)
			(stroke
				(width 0.1)
				(type default)
			)
			(layer "F.Fab")
		)
		(fp_line
			(start -0.67945 -0.305054)
			(end -0.12065 -0.305054)
			(stroke
				(width 0.1)
				(type default)
			)
			(layer "F.Fab")
		)
		(fp_line
			(start -0.12065 -0.305054)
			(end -0.12065 -0.2794)
			(stroke
				(width 0.1)
				(type default)
			)
			(layer "F.Fab")
		)
		(pad "1" smd circle
			(at -0.40005 0 270)
			(size 0 0)
			(layers "F.Cu" "F.Mask" "F.Paste")
			(net "HSC_CSOUT")
		)
		(pad "2" smd circle
			(at 0.40005 0 270)
			(size 0 0)
			(layers "F.Cu" "F.Mask" "F.Paste")
			(net "A_HSC_HIGH")
		)
	)
	(footprint ""
		(layer "F.Cu")
		(at 368.734594 -34.546286 180)
		(property "Reference" "C698"
			(at 0 0 180)
			(layer "F.SilkS")
			(hide yes)
			(effects
				(font
					(size 1.27 1.27)
				)
			)
		)
		(property "Value" ""
			(at 0 0 180)
			(layer "F.Fab")
			(effects
				(font
					(size 1.27 1.27)
				)
			)
		)
		(duplicate_pad_numbers_are_jumpers no)
		(fp_line
			(start 0.299974 0.150114)
			(end -0.299974 0.150114)
			(stroke
				(width 0.1)
				(type default)
			)
			(layer "F.Fab")
		)
		(fp_line
			(start 0.299974 -0.150114)
			(end 0.299974 0.150114)
			(stroke
				(width 0.1)
				(type default)
			)
			(layer "F.Fab")
		)
		(fp_line
			(start -0.299974 0.150114)
			(end -0.299974 -0.150114)
			(stroke
				(width 0.1)
				(type default)
			)
			(layer "F.Fab")
		)
		(fp_line
			(start -0.299974 -0.150114)
			(end 0.299974 -0.150114)
			(stroke
				(width 0.1)
				(type default)
			)
			(layer "F.Fab")
		)
		(pad "1" smd rect
			(at -0.2667 0 180)
			(size 0.3048 0.381)
			(layers "F.Cu" "F.Mask" "F.Paste")
			(net "P5E_PEX3_STN2_TX_DP<47>")
		)
		(pad "2" smd rect
			(at 0.2667 0 180)
			(size 0.3048 0.381)
			(layers "F.Cu" "F.Mask" "F.Paste")
			(net "P5E_PEX3_STN2_TX_C_DP<47>")
		)
	)
	(footprint ""
		(layer "F.Cu")
		(at 242.006882 -211.272882 -90)
		(property "Reference" "R479"
			(at 0 0 270)
			(layer "F.SilkS")
			(hide yes)
			(effects
				(font
					(size 1.27 1.27)
				)
			)
		)
		(property "Value" ""
			(at 0 0 270)
			(layer "F.Fab")
			(effects
				(font
					(size 1.27 1.27)
				)
			)
		)
		(duplicate_pad_numbers_are_jumpers no)
		(fp_line
			(start -0.7874 0.4064)
			(end -0.7874 -0.4064)
			(stroke
				(width 0.1524)
				(type default)
			)
			(layer "F.SilkS")
		)
		(fp_line
			(start 0.7874 0.4064)
			(end -0.7874 0.4064)
			(stroke
				(width 0.1524)
				(type default)
			)
			(layer "F.SilkS")
		)
		(fp_line
			(start -0.7874 -0.4064)
			(end 0.7874 -0.4064)
			(stroke
				(width 0.1524)
				(type default)
			)
			(layer "F.SilkS")
		)
		(fp_line
			(start 0.7874 -0.4064)
			(end 0.7874 0.4064)
			(stroke
				(width 0.1524)
				(type default)
			)
			(layer "F.SilkS")
		)
		(fp_line
			(start -0.67945 0.3048)
			(end -0.67945 -0.305054)
			(stroke
				(width 0.1)
				(type default)
			)
			(layer "F.Fab")
		)
		(fp_line
			(start -0.12065 0.3048)
			(end -0.67945 0.3048)
			(stroke
				(width 0.1)
				(type default)
			)
			(layer "F.Fab")
		)
		(fp_line
			(start 0.120396 0.3048)
			(end 0.120396 0.2794)
			(stroke
				(width 0.1)
				(type default)
			)
			(layer "F.Fab")
		)
		(fp_line
			(start 0.67945 0.3048)
			(end 0.120396 0.3048)
			(stroke
				(width 0.1)
				(type default)
			)
			(layer "F.Fab")
		)
		(fp_line
			(start -0.12065 0.2794)
			(end -0.12065 0.3048)
			(stroke
				(width 0.1)
				(type default)
			)
			(layer "F.Fab")
		)
		(fp_line
			(start 0.120396 0.2794)
			(end -0.12065 0.2794)
			(stroke
				(width 0.1)
				(type default)
			)
			(layer "F.Fab")
		)
		(fp_line
			(start -0.12065 -0.2794)
			(end 0.12065 -0.2794)
			(stroke
				(width 0.1)
				(type default)
			)
			(layer "F.Fab")
		)
		(fp_line
			(start 0.12065 -0.2794)
			(end 0.12065 -0.3048)
			(stroke
				(width 0.1)
				(type default)
			)
			(layer "F.Fab")
		)
		(fp_line
			(start 0.12065 -0.3048)
			(end 0.67945 -0.3048)
			(stroke
				(width 0.1)
				(type default)
			)
			(layer "F.Fab")
		)
		(fp_line
			(start 0.67945 -0.3048)
			(end 0.67945 0.3048)
			(stroke
				(width 0.1)
				(type default)
			)
			(layer "F.Fab")
		)
		(fp_line
			(start -0.67945 -0.305054)
			(end -0.12065 -0.305054)
			(stroke
				(width 0.1)
				(type default)
			)
			(layer "F.Fab")
		)
		(fp_line
			(start -0.12065 -0.305054)
			(end -0.12065 -0.2794)
			(stroke
				(width 0.1)
				(type default)
			)
			(layer "F.Fab")
		)
		(pad "1" smd circle
			(at -0.40005 0 270)
			(size 0 0)
			(layers "F.Cu" "F.Mask" "F.Paste")
			(net "P3V3")
		)
		(pad "2" smd circle
			(at 0.40005 0 270)
			(size 0 0)
			(layers "F.Cu" "F.Mask" "F.Paste")
			(net "P3V3_SCALED")
		)
	)
	(footprint ""
		(layer "F.Cu")
		(at 137.871962 -259.346192)
		(property "Reference" "R1322"
			(at 0 0 0)
			(layer "F.SilkS")
			(hide yes)
			(effects
				(font
					(size 1.27 1.27)
				)
			)
		)
		(property "Value" ""
			(at 0 0 0)
			(layer "F.Fab")
			(effects
				(font
					(size 1.27 1.27)
				)
			)
		)
		(duplicate_pad_numbers_are_jumpers no)
		(fp_line
			(start -0.7874 -0.4064)
			(end 0.7874 -0.4064)
			(stroke
				(width 0.1524)
				(type default)
			)
			(layer "F.SilkS")
		)
		(fp_line
			(start -0.7874 0.4064)
			(end -0.7874 -0.4064)
			(stroke
				(width 0.1524)
				(type default)
			)
			(layer "F.SilkS")
		)
		(fp_line
			(start 0.7874 -0.4064)
			(end 0.7874 0.4064)
			(stroke
				(width 0.1524)
				(type default)
			)
			(layer "F.SilkS")
		)
		(fp_line
			(start 0.7874 0.4064)
			(end -0.7874 0.4064)
			(stroke
				(width 0.1524)
				(type default)
			)
			(layer "F.SilkS")
		)
		(fp_line
			(start -0.67945 -0.305054)
			(end -0.12065 -0.305054)
			(stroke
				(width 0.1)
				(type default)
			)
			(layer "F.Fab")
		)
		(fp_line
			(start -0.67945 0.3048)
			(end -0.67945 -0.305054)
			(stroke
				(width 0.1)
				(type default)
			)
			(layer "F.Fab")
		)
		(fp_line
			(start -0.12065 -0.305054)
			(end -0.12065 -0.2794)
			(stroke
				(width 0.1)
				(type default)
			)
			(layer "F.Fab")
		)
		(fp_line
			(start -0.12065 -0.2794)
			(end 0.12065 -0.2794)
			(stroke
				(width 0.1)
				(type default)
			)
			(layer "F.Fab")
		)
		(fp_line
			(start -0.12065 0.2794)
			(end -0.12065 0.3048)
			(stroke
				(width 0.1)
				(type default)
			)
			(layer "F.Fab")
		)
		(fp_line
			(start -0.12065 0.3048)
			(end -0.67945 0.3048)
			(stroke
				(width 0.1)
				(type default)
			)
			(layer "F.Fab")
		)
		(fp_line
			(start 0.120396 0.2794)
			(end -0.12065 0.2794)
			(stroke
				(width 0.1)
				(type default)
			)
			(layer "F.Fab")
		)
		(fp_line
			(start 0.120396 0.3048)
			(end 0.120396 0.2794)
			(stroke
				(width 0.1)
				(type default)
			)
			(layer "F.Fab")
		)
		(fp_line
			(start 0.12065 -0.3048)
			(end 0.67945 -0.3048)
			(stroke
				(width 0.1)
				(type default)
			)
			(layer "F.Fab")
		)
		(fp_line
			(start 0.12065 -0.2794)
			(end 0.12065 -0.3048)
			(stroke
				(width 0.1)
				(type default)
			)
			(layer "F.Fab")
		)
		(fp_line
			(start 0.67945 -0.3048)
			(end 0.67945 0.3048)
			(stroke
				(width 0.1)
				(type default)
			)
			(layer "F.Fab")
		)
		(fp_line
			(start 0.67945 0.3048)
			(end 0.120396 0.3048)
			(stroke
				(width 0.1)
				(type default)
			)
			(layer "F.Fab")
		)
		(pad "1" smd circle
			(at -0.40005 0)
			(size 0 0)
			(layers "F.Cu" "F.Mask" "F.Paste")
			(net "PEX1_SYS_ERR_N")
		)
		(pad "2" smd circle
			(at 0.40005 0)
			(size 0 0)
			(layers "F.Cu" "F.Mask" "F.Paste")
			(net "PEX1_SYS_ERR_R_N")
		)
	)
	(footprint ""
		(layer "F.Cu")
		(at 402.795232 -35.48253)
		(property "Reference" "U397"
			(at -2.540762 0.63373 90)
			(unlocked yes)
			(layer "F.SilkS")
			(effects
				(font
					(size 0.7874 0.5842)
					(thickness 0.1524)
				)
				(justify left)
			)
		)
		(property "Value" ""
			(at 0 0 0)
			(layer "F.Fab")
			(effects
				(font
					(size 1.27 1.27)
				)
			)
		)
		(duplicate_pad_numbers_are_jumpers no)
		(fp_line
			(start -1.3462 -1.1938)
			(end -1.3462 1.1684)
			(stroke
				(width 0.1524)
				(type default)
			)
			(layer "F.SilkS")
		)
		(fp_line
			(start -1.3462 1.1938)
			(end 1.3462 1.1938)
			(stroke
				(width 0.1524)
				(type default)
			)
			(layer "F.SilkS")
		)
		(fp_line
			(start 1.3462 -1.1938)
			(end -1.3462 -1.1938)
			(stroke
				(width 0.1524)
				(type default)
			)
			(layer "F.SilkS")
		)
		(fp_line
			(start 1.3462 1.1938)
			(end 1.3462 -1.1938)
			(stroke
				(width 0.1524)
				(type default)
			)
			(layer "F.SilkS")
		)
		(fp_poly
			(pts
				(xy -1.447038 -0.760476) (xy -2.052066 -0.457962) (xy -2.052066 -1.06299)
			)
			(stroke
				(width 0)
				(type default)
			)
			(fill yes)
			(layer "F.SilkS")
		)
		(fp_line
			(start -0.674878 -1.124966)
			(end -0.674878 1.124966)
			(stroke
				(width 0.1)
				(type default)
			)
			(layer "F.Fab")
		)
		(fp_line
			(start -0.674878 1.124966)
			(end 0.674878 1.124966)
			(stroke
				(width 0.1)
				(type default)
			)
			(layer "F.Fab")
		)
		(fp_line
			(start 0.674878 -1.124966)
			(end -0.674878 -1.124966)
			(stroke
				(width 0.1)
				(type default)
			)
			(layer "F.Fab")
		)
		(fp_line
			(start 0.674878 1.124966)
			(end 0.674878 -1.124966)
			(stroke
				(width 0.1)
				(type default)
			)
			(layer "F.Fab")
		)
		(fp_poly
			(pts
				(xy -1.447038 -0.760476) (xy -2.052066 -0.457962) (xy -2.052066 -1.06299)
			)
			(stroke
				(width 0)
				(type default)
			)
			(fill yes)
			(layer "F.Fab")
		)
		(pad "1" smd rect
			(at -0.899922 -0.750062)
			(size 0.6096 0.6096)
			(layers "F.Cu" "F.Mask" "F.Paste")
			(net "PWRGD_P3V3_SSD14_R")
		)
		(pad "2" smd rect
			(at -0.899922 0 90)
			(size 0.4064 0.6096)
			(layers "F.Cu" "F.Mask" "F.Paste")
			(net "RST_SMB_SSD14_N")
		)
		(pad "3" smd rect
			(at -0.899922 0.750062)
			(size 0.6096 0.6096)
			(layers "F.Cu" "F.Mask" "F.Paste")
			(net "GND")
		)
		(pad "4" smd rect
			(at 0.899922 0.750062)
			(size 0.6096 0.6096)
			(layers "F.Cu" "F.Mask" "F.Paste")
			(net "RST_SMB_SSD14_ISO_N")
		)
		(pad "5" smd rect
			(at 0.899922 -0.750062)
			(size 0.6096 0.6096)
			(layers "F.Cu" "F.Mask" "F.Paste")
			(net "P3V3_AUX")
		)
	)
	(footprint ""
		(layer "F.Cu")
		(at 118.688358 -277.639272 180)
		(property "Reference" "PC111"
			(at 0 0 180)
			(layer "F.SilkS")
			(hide yes)
			(effects
				(font
					(size 1.27 1.27)
				)
			)
		)
		(property "Value" ""
			(at 0 0 180)
			(layer "F.Fab")
			(effects
				(font
					(size 1.27 1.27)
				)
			)
		)
		(duplicate_pad_numbers_are_jumpers no)
		(fp_line
			(start 1.524 0.762)
			(end -1.524 0.762)
			(stroke
				(width 0.1524)
				(type default)
			)
			(layer "F.SilkS")
		)
		(fp_line
			(start 1.524 -0.762)
			(end 1.524 0.762)
			(stroke
				(width 0.1524)
				(type default)
			)
			(layer "F.SilkS")
		)
		(fp_line
			(start -1.524 0.762)
			(end -1.524 -0.762)
			(stroke
				(width 0.1524)
				(type default)
			)
			(layer "F.SilkS")
		)
		(fp_line
			(start -1.524 -0.762)
			(end 1.524 -0.762)
			(stroke
				(width 0.1524)
				(type default)
			)
			(layer "F.SilkS")
		)
		(fp_line
			(start 1.1049 0.724916)
			(end 1.1049 -0.724916)
			(stroke
				(width 0.1)
				(type default)
			)
			(layer "F.Fab")
		)
		(fp_line
			(start 1.1049 -0.724916)
			(end -1.1049 -0.724916)
			(stroke
				(width 0.1)
				(type default)
			)
			(layer "F.Fab")
		)
		(fp_line
			(start -1.1049 0.724916)
			(end 1.1049 0.724916)
			(stroke
				(width 0.1)
				(type default)
			)
			(layer "F.Fab")
		)
		(fp_line
			(start -1.1049 -0.724916)
			(end -1.1049 0.724916)
			(stroke
				(width 0.1)
				(type default)
			)
			(layer "F.Fab")
		)
		(pad "1" smd rect
			(at -0.889 0)
			(size 1.016 1.27)
			(layers "F.Cu" "F.Mask" "F.Paste")
			(net "SW_P12V_P0V8_PEX1_FLT")
		)
		(pad "2" smd rect
			(at 0.889 0)
			(size 1.016 1.27)
			(layers "F.Cu" "F.Mask" "F.Paste")
			(net "GND")
		)
	)
	(footprint ""
		(layer "F.Cu")
		(at 283.262324 -22.955504 -90)
		(property "Reference" "C2737"
			(at 0 0 270)
			(layer "F.SilkS")
			(hide yes)
			(effects
				(font
					(size 1.27 1.27)
				)
			)
		)
		(property "Value" ""
			(at 0 0 270)
			(layer "F.Fab")
			(effects
				(font
					(size 1.27 1.27)
				)
			)
		)
		(duplicate_pad_numbers_are_jumpers no)
		(fp_line
			(start -0.7874 0.4064)
			(end -0.7874 -0.4064)
			(stroke
				(width 0.1524)
				(type default)
			)
			(layer "F.SilkS")
		)
		(fp_line
			(start 0.7874 0.4064)
			(end -0.7874 0.4064)
			(stroke
				(width 0.1524)
				(type default)
			)
			(layer "F.SilkS")
		)
		(fp_line
			(start -0.7874 -0.4064)
			(end 0.7874 -0.4064)
			(stroke
				(width 0.1524)
				(type default)
			)
			(layer "F.SilkS")
		)
		(fp_line
			(start 0.7874 -0.4064)
			(end 0.7874 0.4064)
			(stroke
				(width 0.1524)
				(type default)
			)
			(layer "F.SilkS")
		)
		(fp_line
			(start -0.67945 0.3048)
			(end -0.67945 -0.305054)
			(stroke
				(width 0.1)
				(type default)
			)
			(layer "F.Fab")
		)
		(fp_line
			(start -0.12065 0.3048)
			(end -0.67945 0.3048)
			(stroke
				(width 0.1)
				(type default)
			)
			(layer "F.Fab")
		)
		(fp_line
			(start 0.120396 0.3048)
			(end 0.120396 0.2794)
			(stroke
				(width 0.1)
				(type default)
			)
			(layer "F.Fab")
		)
		(fp_line
			(start 0.67945 0.3048)
			(end 0.120396 0.3048)
			(stroke
				(width 0.1)
				(type default)
			)
			(layer "F.Fab")
		)
		(fp_line
			(start -0.12065 0.2794)
			(end -0.12065 0.3048)
			(stroke
				(width 0.1)
				(type default)
			)
			(layer "F.Fab")
		)
		(fp_line
			(start 0.120396 0.2794)
			(end -0.12065 0.2794)
			(stroke
				(width 0.1)
				(type default)
			)
			(layer "F.Fab")
		)
		(fp_line
			(start -0.12065 -0.2794)
			(end 0.12065 -0.2794)
			(stroke
				(width 0.1)
				(type default)
			)
			(layer "F.Fab")
		)
		(fp_line
			(start 0.12065 -0.2794)
			(end 0.12065 -0.3048)
			(stroke
				(width 0.1)
				(type default)
			)
			(layer "F.Fab")
		)
		(fp_line
			(start 0.12065 -0.3048)
			(end 0.67945 -0.3048)
			(stroke
				(width 0.1)
				(type default)
			)
			(layer "F.Fab")
		)
		(fp_line
			(start 0.67945 -0.3048)
			(end 0.67945 0.3048)
			(stroke
				(width 0.1)
				(type default)
			)
			(layer "F.Fab")
		)
		(fp_line
			(start -0.67945 -0.305054)
			(end -0.12065 -0.305054)
			(stroke
				(width 0.1)
				(type default)
			)
			(layer "F.Fab")
		)
		(fp_line
			(start -0.12065 -0.305054)
			(end -0.12065 -0.2794)
			(stroke
				(width 0.1)
				(type default)
			)
			(layer "F.Fab")
		)
		(pad "1" smd circle
			(at -0.40005 0 270)
			(size 0 0)
			(layers "F.Cu" "F.Mask" "F.Paste")
			(net "GND")
		)
		(pad "2" smd circle
			(at 0.40005 0 270)
			(size 0 0)
			(layers "F.Cu" "F.Mask" "F.Paste")
			(net "P3V3_AUX")
		)
	)
)
